(kicad_pcb
	(version 20260206)
	(generator "pcbnew")
	(generator_version "10.0")
	(general
		(thickness 1.6)
		(legacy_teardrops no)
	)
	(paper "A4")
	(title_block
		(title "peb — Lightning_PEB_BRD.brd")
		(comment 1 "Lightning (Wiwynn / Facebook NVMe JBOF) / footprints 209-216 of 2563")
	)
	(layers
		(0 "F.Cu" signal "TOP")
		(4 "In1.Cu" signal "L2GND")
		(6 "In2.Cu" signal "L3")
		(8 "In3.Cu" signal "L4VCC")
		(10 "In4.Cu" signal "L5VCC")
		(12 "In5.Cu" signal "L6")
		(14 "In6.Cu" signal "L7GND")
		(2 "B.Cu" signal "BOTTOM")
		(9 "F.Adhes" user "F.Adhesive")
		(11 "B.Adhes" user "B.Adhesive")
		(13 "F.Paste" user "Package Geometry/Pastemask Top")
		(15 "B.Paste" user "Package Geometry/Pastemask Bottom")
		(5 "F.SilkS" user "Ref Des/Silkscreen Top")
		(7 "B.SilkS" user "Ref Des/Silkscreen Bottom")
		(1 "F.Mask" user "Board Geometry/Soldermask Top")
		(3 "B.Mask" user "Board Geometry/Soldermask Bottom")
		(17 "Dwgs.User" user "User.Drawings")
		(19 "Cmts.User" user "User.Comments")
		(21 "Eco1.User" user "User.Eco1")
		(23 "Eco2.User" user "User.Eco2")
		(25 "Edge.Cuts" user "Board Geometry/Outline")
		(27 "Margin" user)
		(31 "F.CrtYd" user "Package Geometry/Place Bound Top")
		(29 "B.CrtYd" user "Package Geometry/Place Bound Bottom")
		(35 "F.Fab" user "Ref Des/Assembly Top")
		(33 "B.Fab" user "Ref Des/Assembly Bottom")
	)
	(footprint ""
		(layer "F.Cu")
		(at 30.936946 -91.888056)
		(property "Reference" "C3216"
			(at 0 0 0)
			(layer "F.SilkS")
			(hide yes)
			(effects
				(font
					(size 1.27 1.27)
				)
			)
		)
		(property "Value" "SCD1U25V2KX-2-GP"
			(at 1.1811 -2.7051 0)
			(unlocked yes)
			(layer "F.Fab")
			(hide yes)
			(effects
				(font
					(size 1.016 1.016)
					(thickness 0.1524)
				)
			)
		)
		(property "Device Type" "C402H22"
			(at 1.1811 -4.2291 0)
			(unlocked yes)
			(layer "F.Fab")
			(hide yes)
			(effects
				(font
					(size 1.016 1.016)
					(thickness 0.1524)
				)
			)
		)
		(duplicate_pad_numbers_are_jumpers no)
		(fp_rect
			(start -0.4318 0.9525)
			(end 0.4318 -0.9525)
			(stroke
				(width 0)
				(type default)
			)
			(fill no)
			(layer "F.CrtYd")
		)
		(fp_rect
			(start -0.4318 0.9525)
			(end 0.4318 -0.9525)
			(stroke
				(width 0)
				(type default)
			)
			(fill no)
			(layer "F.Fab")
		)
		(pad "1" smd custom
			(at 0 -0.4445)
			(size 0.1524 0.1524)
			(layers "F.Cu" "F.Mask" "F.Paste")
			(net "P3V3_STBY")
			(options
				(clearance outline)
				(anchor circle)
			)
			(primitives
				(gr_poly
					(pts
						(arc
							(start 0.3048 -0.2032)
							(mid 0.275042 -0.275042)
							(end 0.2032 -0.3048)
						)
						(arc
							(start -0.2032 -0.3048)
							(mid -0.275042 -0.275042)
							(end -0.3048 -0.2032)
						)
						(arc
							(start -0.3048 0.2032)
							(mid -0.275042 0.275042)
							(end -0.2032 0.3048)
						)
						(arc
							(start 0.2032 0.3048)
							(mid 0.275042 0.275042)
							(end 0.3048 0.2032)
						)
					)
					(width 0)
					(fill yes)
				)
			)
		)
		(pad "2" smd custom
			(at 0 0.4445)
			(size 0.1524 0.1524)
			(layers "F.Cu" "F.Mask" "F.Paste")
			(net "GND")
			(options
				(clearance outline)
				(anchor circle)
			)
			(primitives
				(gr_poly
					(pts
						(arc
							(start 0.3048 -0.2032)
							(mid 0.275042 -0.275042)
							(end 0.2032 -0.3048)
						)
						(arc
							(start -0.2032 -0.3048)
							(mid -0.275042 -0.275042)
							(end -0.3048 -0.2032)
						)
						(arc
							(start -0.3048 0.2032)
							(mid -0.275042 0.275042)
							(end -0.2032 0.3048)
						)
						(arc
							(start 0.2032 0.3048)
							(mid 0.275042 0.275042)
							(end 0.3048 0.2032)
						)
					)
					(width 0)
					(fill yes)
				)
			)
		)
	)
	(footprint ""
		(layer "F.Cu")
		(at 65.4812 -156.0576 90)
		(property "Reference" "PC75"
			(at 0 0 90)
			(layer "F.SilkS")
			(hide yes)
			(effects
				(font
					(size 1.27 1.27)
				)
			)
		)
		(property "Value" "SC22U6D3V5MX-5-GP"
			(at -0.0762 -6.1214 90)
			(unlocked yes)
			(layer "F.Fab")
			(hide yes)
			(effects
				(font
					(size 1.016 1.016)
					(thickness 0.1524)
				)
			)
		)
		(property "Device Type" "C805H56"
			(at -0.0762 -8.1534 90)
			(unlocked yes)
			(layer "F.Fab")
			(hide yes)
			(effects
				(font
					(size 1.016 1.016)
					(thickness 0.1524)
				)
			)
		)
		(duplicate_pad_numbers_are_jumpers no)
		(fp_line
			(start 0.635 0)
			(end -0.635 0)
			(stroke
				(width 0.508)
				(type default)
			)
			(layer "F.SilkS")
		)
		(fp_rect
			(start -0.9652 1.778)
			(end 0.9652 -1.778)
			(stroke
				(width 0)
				(type default)
			)
			(fill no)
			(layer "F.CrtYd")
		)
		(fp_poly
			(pts
				(xy -0.9652 -1.778) (xy 0.9652 -1.778) (xy 0.9652 1.778) (xy -0.9652 1.778)
			)
			(stroke
				(width 0)
				(type default)
			)
			(fill no)
			(layer "F.Fab")
		)
		(pad "1" smd rect
			(at 0 -0.9652 90)
			(size 1.397 1.143)
			(layers "F.Cu" "F.Mask" "F.Paste")
			(net "P1V53_PWR")
		)
		(pad "2" smd rect
			(at 0 0.9652 90)
			(size 1.397 1.143)
			(layers "F.Cu" "F.Mask" "F.Paste")
			(net "GND")
		)
	)
	(footprint ""
		(layer "F.Cu")
		(at 220.345 -3.683 180)
		(property "Reference" "R275"
			(at 0 0 180)
			(layer "F.SilkS")
			(hide yes)
			(effects
				(font
					(size 1.27 1.27)
				)
			)
		)
		(property "Value" "0R2J-2-GP"
			(at 0.064008 -3.993896 180)
			(unlocked yes)
			(layer "F.Fab")
			(hide yes)
			(effects
				(font
					(size 1.016 1.016)
					(thickness 0.1524)
				)
			)
		)
		(property "Device Type" "R402H16"
			(at 0.064008 -5.517896 180)
			(unlocked yes)
			(layer "F.Fab")
			(hide yes)
			(effects
				(font
					(size 1.016 1.016)
					(thickness 0.1524)
				)
			)
		)
		(duplicate_pad_numbers_are_jumpers no)
		(fp_line
			(start 0.508 -0.9398)
			(end -0.508 -0.9398)
			(stroke
				(width 0.1524)
				(type default)
			)
			(layer "F.SilkS")
		)
		(fp_line
			(start -0.508 -0.9398)
			(end -0.508 0.9398)
			(stroke
				(width 0.1524)
				(type default)
			)
			(layer "F.SilkS")
		)
		(fp_rect
			(start -0.508 0.9398)
			(end 0.508 -0.9398)
			(stroke
				(width 0)
				(type default)
			)
			(fill no)
			(layer "F.CrtYd")
		)
		(fp_rect
			(start -0.508 0.9398)
			(end 0.508 -0.9398)
			(stroke
				(width 0)
				(type default)
			)
			(fill no)
			(layer "F.Fab")
		)
		(pad "1" smd custom
			(at 0 -0.4445 180)
			(size 0.1397 0.1397)
			(layers "F.Cu" "F.Mask" "F.Paste")
			(net "UART_SWITCH_R")
			(options
				(clearance outline)
				(anchor circle)
			)
			(primitives
				(gr_poly
					(pts
						(arc
							(start -0.1778 -0.2794)
							(mid -0.249642 -0.249642)
							(end -0.2794 -0.1778)
						)
						(arc
							(start -0.2794 0.1778)
							(mid -0.249642 0.249642)
							(end -0.1778 0.2794)
						)
						(arc
							(start 0.1778 0.2794)
							(mid 0.249642 0.249642)
							(end 0.2794 0.1778)
						)
						(arc
							(start 0.2794 -0.1778)
							(mid 0.249642 -0.249642)
							(end 0.1778 -0.2794)
						)
					)
					(width 0)
					(fill yes)
				)
			)
		)
		(pad "2" smd custom
			(at 0 0.4445 180)
			(size 0.1397 0.1397)
			(layers "F.Cu" "F.Mask" "F.Paste")
			(net "BMC_UART_SWITCH_1")
			(options
				(clearance outline)
				(anchor circle)
			)
			(primitives
				(gr_poly
					(pts
						(arc
							(start -0.1778 -0.2794)
							(mid -0.249642 -0.249642)
							(end -0.2794 -0.1778)
						)
						(arc
							(start -0.2794 0.1778)
							(mid -0.249642 0.249642)
							(end -0.1778 0.2794)
						)
						(arc
							(start 0.1778 0.2794)
							(mid 0.249642 0.249642)
							(end 0.2794 0.1778)
						)
						(arc
							(start 0.2794 -0.1778)
							(mid 0.249642 -0.249642)
							(end 0.1778 -0.2794)
						)
					)
					(width 0)
					(fill yes)
				)
			)
		)
	)
	(footprint ""
		(layer "F.Cu")
		(at 222.999046 -203.708 180)
		(property "Reference" "R7949"
			(at 0 0 180)
			(layer "F.SilkS")
			(hide yes)
			(effects
				(font
					(size 1.27 1.27)
				)
			)
		)
		(property "Value" "0R2J-2-GP"
			(at 0.064008 -3.993896 180)
			(unlocked yes)
			(layer "F.Fab")
			(hide yes)
			(effects
				(font
					(size 1.016 1.016)
					(thickness 0.1524)
				)
			)
		)
		(property "Device Type" "R402H16"
			(at 0.064008 -5.517896 180)
			(unlocked yes)
			(layer "F.Fab")
			(hide yes)
			(effects
				(font
					(size 1.016 1.016)
					(thickness 0.1524)
				)
			)
		)
		(duplicate_pad_numbers_are_jumpers no)
		(fp_line
			(start 0.508 -0.9398)
			(end -0.508 -0.9398)
			(stroke
				(width 0.1524)
				(type default)
			)
			(layer "F.SilkS")
		)
		(fp_line
			(start -0.508 -0.9398)
			(end -0.508 0.9398)
			(stroke
				(width 0.1524)
				(type default)
			)
			(layer "F.SilkS")
		)
		(fp_rect
			(start -0.508 0.9398)
			(end 0.508 -0.9398)
			(stroke
				(width 0)
				(type default)
			)
			(fill no)
			(layer "F.CrtYd")
		)
		(fp_rect
			(start -0.508 0.9398)
			(end 0.508 -0.9398)
			(stroke
				(width 0)
				(type default)
			)
			(fill no)
			(layer "F.Fab")
		)
		(pad "1" smd custom
			(at 0 -0.4445 180)
			(size 0.1397 0.1397)
			(layers "F.Cu" "F.Mask" "F.Paste")
			(net "SSD_ATNLED#13")
			(options
				(clearance outline)
				(anchor circle)
			)
			(primitives
				(gr_poly
					(pts
						(arc
							(start -0.1778 -0.2794)
							(mid -0.249642 -0.249642)
							(end -0.2794 -0.1778)
						)
						(arc
							(start -0.2794 0.1778)
							(mid -0.249642 0.249642)
							(end -0.1778 0.2794)
						)
						(arc
							(start 0.1778 0.2794)
							(mid 0.249642 0.249642)
							(end 0.2794 0.1778)
						)
						(arc
							(start 0.2794 -0.1778)
							(mid 0.249642 -0.249642)
							(end 0.1778 -0.2794)
						)
					)
					(width 0)
					(fill yes)
				)
			)
		)
		(pad "2" smd custom
			(at 0 0.4445 180)
			(size 0.1397 0.1397)
			(layers "F.Cu" "F.Mask" "F.Paste")
			(net "SSD_ATNLED#13_R")
			(options
				(clearance outline)
				(anchor circle)
			)
			(primitives
				(gr_poly
					(pts
						(arc
							(start -0.1778 -0.2794)
							(mid -0.249642 -0.249642)
							(end -0.2794 -0.1778)
						)
						(arc
							(start -0.2794 0.1778)
							(mid -0.249642 0.249642)
							(end -0.1778 0.2794)
						)
						(arc
							(start 0.1778 0.2794)
							(mid 0.249642 0.249642)
							(end 0.2794 0.1778)
						)
						(arc
							(start 0.2794 -0.1778)
							(mid 0.249642 -0.249642)
							(end 0.1778 -0.2794)
						)
					)
					(width 0)
					(fill yes)
				)
			)
		)
	)
	(footprint ""
		(layer "F.Cu")
		(at 54.6608 -113.284 90)
		(property "Reference" "R440"
			(at 0 0 90)
			(layer "F.SilkS")
			(hide yes)
			(effects
				(font
					(size 1.27 1.27)
				)
			)
		)
		(property "Value" "4K7R2F-GP"
			(at 0.064008 -3.993896 90)
			(unlocked yes)
			(layer "F.Fab")
			(hide yes)
			(effects
				(font
					(size 1.016 1.016)
					(thickness 0.1524)
				)
			)
		)
		(property "Device Type" "R402H16"
			(at 0.064008 -5.517896 90)
			(unlocked yes)
			(layer "F.Fab")
			(hide yes)
			(effects
				(font
					(size 1.016 1.016)
					(thickness 0.1524)
				)
			)
		)
		(duplicate_pad_numbers_are_jumpers no)
		(fp_line
			(start 0.508 -0.9398)
			(end -0.508 -0.9398)
			(stroke
				(width 0.1524)
				(type default)
			)
			(layer "F.SilkS")
		)
		(fp_line
			(start -0.508 -0.9398)
			(end -0.508 0.9398)
			(stroke
				(width 0.1524)
				(type default)
			)
			(layer "F.SilkS")
		)
		(fp_rect
			(start -0.508 0.9398)
			(end 0.508 -0.9398)
			(stroke
				(width 0)
				(type default)
			)
			(fill no)
			(layer "F.CrtYd")
		)
		(fp_rect
			(start -0.508 0.9398)
			(end 0.508 -0.9398)
			(stroke
				(width 0)
				(type default)
			)
			(fill no)
			(layer "F.Fab")
		)
		(pad "1" smd custom
			(at 0 -0.4445 90)
			(size 0.1397 0.1397)
			(layers "F.Cu" "F.Mask" "F.Paste")
			(net "BMC_I2C13_MINI7_SCL_S")
			(options
				(clearance outline)
				(anchor circle)
			)
			(primitives
				(gr_poly
					(pts
						(arc
							(start -0.1778 -0.2794)
							(mid -0.249642 -0.249642)
							(end -0.2794 -0.1778)
						)
						(arc
							(start -0.2794 0.1778)
							(mid -0.249642 0.249642)
							(end -0.1778 0.2794)
						)
						(arc
							(start 0.1778 0.2794)
							(mid 0.249642 0.249642)
							(end 0.2794 0.1778)
						)
						(arc
							(start 0.2794 -0.1778)
							(mid 0.249642 -0.249642)
							(end 0.1778 -0.2794)
						)
					)
					(width 0)
					(fill yes)
				)
			)
		)
		(pad "2" smd custom
			(at 0 0.4445 90)
			(size 0.1397 0.1397)
			(layers "F.Cu" "F.Mask" "F.Paste")
			(net "P3V3_STBY")
			(options
				(clearance outline)
				(anchor circle)
			)
			(primitives
				(gr_poly
					(pts
						(arc
							(start -0.1778 -0.2794)
							(mid -0.249642 -0.249642)
							(end -0.2794 -0.1778)
						)
						(arc
							(start -0.2794 0.1778)
							(mid -0.249642 0.249642)
							(end -0.1778 0.2794)
						)
						(arc
							(start 0.1778 0.2794)
							(mid 0.249642 0.249642)
							(end 0.2794 0.1778)
						)
						(arc
							(start 0.2794 -0.1778)
							(mid 0.249642 -0.249642)
							(end 0.1778 -0.2794)
						)
					)
					(width 0)
					(fill yes)
				)
			)
		)
	)
	(footprint ""
		(layer "F.Cu")
		(at 325.991982 -212.420454 180)
		(property "Reference" "C62"
			(at 0 0 180)
			(layer "F.SilkS")
			(hide yes)
			(effects
				(font
					(size 1.27 1.27)
				)
			)
		)
		(property "Value" "SCD22U10V2KX-1GP"
			(at 1.1811 -2.7051 180)
			(unlocked yes)
			(layer "F.Fab")
			(hide yes)
			(effects
				(font
					(size 1.016 1.016)
					(thickness 0.1524)
				)
			)
		)
		(property "Device Type" "C402H22"
			(at 1.1811 -4.2291 180)
			(unlocked yes)
			(layer "F.Fab")
			(hide yes)
			(effects
				(font
					(size 1.016 1.016)
					(thickness 0.1524)
				)
			)
		)
		(duplicate_pad_numbers_are_jumpers no)
		(fp_rect
			(start -0.4318 0.9525)
			(end 0.4318 -0.9525)
			(stroke
				(width 0)
				(type default)
			)
			(fill no)
			(layer "F.CrtYd")
		)
		(fp_rect
			(start -0.4318 0.9525)
			(end 0.4318 -0.9525)
			(stroke
				(width 0)
				(type default)
			)
			(fill no)
			(layer "F.Fab")
		)
		(pad "1" smd custom
			(at 0 -0.4445 180)
			(size 0.1524 0.1524)
			(layers "F.Cu" "F.Mask" "F.Paste")
			(net "PCIE_TX_CAP_P20")
			(options
				(clearance outline)
				(anchor circle)
			)
			(primitives
				(gr_poly
					(pts
						(arc
							(start 0.3048 -0.2032)
							(mid 0.275042 -0.275042)
							(end 0.2032 -0.3048)
						)
						(arc
							(start -0.2032 -0.3048)
							(mid -0.275042 -0.275042)
							(end -0.3048 -0.2032)
						)
						(arc
							(start -0.3048 0.2032)
							(mid -0.275042 0.275042)
							(end -0.2032 0.3048)
						)
						(arc
							(start 0.2032 0.3048)
							(mid 0.275042 0.275042)
							(end 0.3048 0.2032)
						)
					)
					(width 0)
					(fill yes)
				)
			)
		)
		(pad "2" smd custom
			(at 0 0.4445 180)
			(size 0.1524 0.1524)
			(layers "F.Cu" "F.Mask" "F.Paste")
			(net "PCIE_TX_P20")
			(options
				(clearance outline)
				(anchor circle)
			)
			(primitives
				(gr_poly
					(pts
						(arc
							(start 0.3048 -0.2032)
							(mid 0.275042 -0.275042)
							(end 0.2032 -0.3048)
						)
						(arc
							(start -0.2032 -0.3048)
							(mid -0.275042 -0.275042)
							(end -0.3048 -0.2032)
						)
						(arc
							(start -0.3048 0.2032)
							(mid -0.275042 0.275042)
							(end -0.2032 0.3048)
						)
						(arc
							(start 0.2032 0.3048)
							(mid 0.275042 0.275042)
							(end 0.3048 0.2032)
						)
					)
					(width 0)
					(fill yes)
				)
			)
		)
	)
	(footprint ""
		(layer "F.Cu")
		(at 79.591916 -212.420454 180)
		(property "Reference" "C352"
			(at 0 0 180)
			(layer "F.SilkS")
			(hide yes)
			(effects
				(font
					(size 1.27 1.27)
				)
			)
		)
		(property "Value" "SCD22U10V2KX-1GP"
			(at 1.1811 -2.7051 180)
			(unlocked yes)
			(layer "F.Fab")
			(hide yes)
			(effects
				(font
					(size 1.016 1.016)
					(thickness 0.1524)
				)
			)
		)
		(property "Device Type" "C402H22"
			(at 1.1811 -4.2291 180)
			(unlocked yes)
			(layer "F.Fab")
			(hide yes)
			(effects
				(font
					(size 1.016 1.016)
					(thickness 0.1524)
				)
			)
		)
		(duplicate_pad_numbers_are_jumpers no)
		(fp_rect
			(start -0.4318 0.9525)
			(end 0.4318 -0.9525)
			(stroke
				(width 0)
				(type default)
			)
			(fill no)
			(layer "F.CrtYd")
		)
		(fp_rect
			(start -0.4318 0.9525)
			(end 0.4318 -0.9525)
			(stroke
				(width 0)
				(type default)
			)
			(fill no)
			(layer "F.Fab")
		)
		(pad "1" smd custom
			(at 0 -0.4445 180)
			(size 0.1524 0.1524)
			(layers "F.Cu" "F.Mask" "F.Paste")
			(net "PCIE_TX_CAP_P68")
			(options
				(clearance outline)
				(anchor circle)
			)
			(primitives
				(gr_poly
					(pts
						(arc
							(start 0.3048 -0.2032)
							(mid 0.275042 -0.275042)
							(end 0.2032 -0.3048)
						)
						(arc
							(start -0.2032 -0.3048)
							(mid -0.275042 -0.275042)
							(end -0.3048 -0.2032)
						)
						(arc
							(start -0.3048 0.2032)
							(mid -0.275042 0.275042)
							(end -0.2032 0.3048)
						)
						(arc
							(start 0.2032 0.3048)
							(mid 0.275042 0.275042)
							(end 0.3048 0.2032)
						)
					)
					(width 0)
					(fill yes)
				)
			)
		)
		(pad "2" smd custom
			(at 0 0.4445 180)
			(size 0.1524 0.1524)
			(layers "F.Cu" "F.Mask" "F.Paste")
			(net "PCIE_TX_P68")
			(options
				(clearance outline)
				(anchor circle)
			)
			(primitives
				(gr_poly
					(pts
						(arc
							(start 0.3048 -0.2032)
							(mid 0.275042 -0.275042)
							(end 0.2032 -0.3048)
						)
						(arc
							(start -0.2032 -0.3048)
							(mid -0.275042 -0.275042)
							(end -0.3048 -0.2032)
						)
						(arc
							(start -0.3048 0.2032)
							(mid -0.275042 0.275042)
							(end -0.2032 0.3048)
						)
						(arc
							(start 0.2032 0.3048)
							(mid 0.275042 0.275042)
							(end 0.3048 0.2032)
						)
					)
					(width 0)
					(fill yes)
				)
			)
		)
	)
	(footprint ""
		(layer "F.Cu")
		(at 135.358886 -82.941414 180)
		(property "Reference" "X2"
			(at 0 0 180)
			(layer "F.SilkS")
			(hide yes)
			(effects
				(font
					(size 1.27 1.27)
				)
			)
		)
		(property "Value" "XTAL-32D768KHZ-137-GP"
			(at 0.0127 -3.6322 180)
			(unlocked yes)
			(layer "F.Fab")
			(hide yes)
			(effects
				(font
					(size 1.016 1.016)
					(thickness 0.1524)
				)
			)
		)
		(property "Device Type" "SMD49-12H34"
			(at 0.0127 -5.1562 180)
			(unlocked yes)
			(layer "F.Fab")
			(hide yes)
			(effects
				(font
					(size 1.016 1.016)
					(thickness 0.1524)
				)
			)
		)
		(duplicate_pad_numbers_are_jumpers no)
		(fp_line
			(start 1.1303 2.2479)
			(end -1.1303 2.2479)
			(stroke
				(width 0.1524)
				(type default)
			)
			(layer "F.SilkS")
		)
		(fp_line
			(start 1.1303 -2.2479)
			(end 1.1303 2.2479)
			(stroke
				(width 0.1524)
				(type default)
			)
			(layer "F.SilkS")
		)
		(fp_line
			(start -1.1303 2.2479)
			(end -1.1303 -2.2479)
			(stroke
				(width 0.1524)
				(type default)
			)
			(layer "F.SilkS")
		)
		(fp_line
			(start -1.1303 -2.2479)
			(end 1.1303 -2.2479)
			(stroke
				(width 0.1524)
				(type default)
			)
			(layer "F.SilkS")
		)
		(fp_rect
			(start -0.7493 1.6002)
			(end 0.7493 -1.6002)
			(stroke
				(width 0)
				(type default)
			)
			(fill no)
			(layer "F.CrtYd")
		)
		(fp_poly
			(pts
				(xy -1.3843 2.5019) (xy -1.3843 -2.5019) (xy 1.3843 -2.5019) (xy 1.3843 -1.6002) (xy -0.7493 -1.6002)
				(xy -0.7493 1.6002) (xy 0.7493 1.6002) (xy 0.7493 -1.5875) (xy 1.3843 -1.5875) (xy 1.3843 2.5019)
			)
			(stroke
				(width 0)
				(type default)
			)
			(fill no)
			(layer "F.CrtYd")
		)
		(fp_rect
			(start -1.3843 2.5019)
			(end 1.3843 -2.5019)
			(stroke
				(width 0)
				(type default)
			)
			(fill no)
			(layer "F.Fab")
		)
		(pad "1" smd rect
			(at 0 -1.2954 180)
			(size 1.7526 1.397)
			(layers "F.Cu" "F.Mask" "F.Paste")
			(net "RTC_OSCI")
		)
		(pad "2" smd rect
			(at 0 1.2954 180)
			(size 1.7526 1.397)
			(layers "F.Cu" "F.Mask" "F.Paste")
			(net "RTC_OSCO")
		)
		(zone
			(layer "F.Cu")
			(hatch none 0.5)
			(connect_pads
				(clearance 0)
			)
			(min_thickness 0.25)
			(keepout
				(tracks allowed)
				(vias not_allowed)
				(pads allowed)
				(copperpour not_allowed)
				(footprints allowed)
			)
			(placement
				(enabled no)
				(sheetname "")
			)
			(fill
				(thermal_gap 0.5)
				(thermal_bridge_width 0.5)
				(island_removal_mode 0)
			)
			(polygon
				(pts
					(xy 136.235186 -82.344514) (xy 136.235186 -83.538314) (xy 134.482586 -83.538314) (xy 134.482586 -82.344514)
				)
			)
		)
	)
)
